# S9S_MB_2U (Grand Teton) — schematic netlist excerpt (pin names and nets, part order shuffled) for the footprints in the layout excerpt that follows; sources: Cadence DE-HDL packaged netlist, KiCad conversion of 03242023_DA0F0TMBIJ0_F0T_Motherboard_J_brd_V01_OCP.brd

C475  Q_CAP  47UF 2.5V 20% X6S  pkg C0603  page 79 : A = PVCCFA_EHV_CPU1 ; B = GND
R3909  Q_RES  33.2 1% CHIP  pkg 0402LF  page 301 : A = SMB_SML1_PMBUS_HSC_SCL ; B = SMB_SML1_PMBUS_HSC_L_SCL
C27  Q_CAP  10UF 16V 10% X6S  pkg C0805  page 90 : A = P12V_S3_AUX_CPU0_NVDIMM ; B = GND

(kicad_pcb
	(version 20260206)
	(generator "pcbnew")
	(generator_version "10.0")
	(general
		(thickness 1.6)
		(legacy_teardrops no)
	)
	(paper "A4")
	(title_block
		(title "03242023_DA0F0TMBIJ0_F0T_Motherboard_J_brd_V01_OCP.brd")
		(comment 1 "Grand Teton / footprints 4854-4856 of 6105")
	)
	(layers
		(0 "F.Cu" signal "TOP")
		(4 "In1.Cu" signal "GND")
		(6 "In2.Cu" signal "IN1")
		(8 "In3.Cu" signal "GND1")
		(10 "In4.Cu" signal "IN2")
		(12 "In5.Cu" signal "GND2")
		(14 "In6.Cu" signal "IN3")
		(16 "In7.Cu" signal "GND3")
		(18 "In8.Cu" signal "VCC")
		(20 "In9.Cu" signal "VCC1")
		(22 "In10.Cu" signal "GND4")
		(24 "In11.Cu" signal "IN4")
		(26 "In12.Cu" signal "GND5")
		(28 "In13.Cu" signal "IN5")
		(30 "In14.Cu" signal "GND6")
		(32 "In15.Cu" signal "IN6")
		(34 "In16.Cu" signal "GND7")
		(2 "B.Cu" signal "BOTTOM")
		(9 "F.Adhes" user "F.Adhesive")
		(11 "B.Adhes" user "B.Adhesive")
		(13 "F.Paste" user "Package Geometry/Pastemask Top")
		(15 "B.Paste" user "Package Geometry/Pastemask Bottom")
		(5 "F.SilkS" user "Ref Des/Silkscreen Top")
		(7 "B.SilkS" user "Ref Des/Silkscreen Bottom")
		(1 "F.Mask" user "Board Geometry/Soldermask Top")
		(3 "B.Mask" user "Board Geometry/Soldermask Bottom")
		(17 "Dwgs.User" user "User.Drawings")
		(19 "Cmts.User" user "User.Comments")
		(21 "Eco1.User" user "User.Eco1")
		(23 "Eco2.User" user "User.Eco2")
		(25 "Edge.Cuts" user "Board Geometry/Outline")
		(27 "Margin" user)
		(31 "F.CrtYd" user "Package Geometry/Place Bound Top")
		(29 "B.CrtYd" user "Package Geometry/Place Bound Bottom")
		(35 "F.Fab" user "Ref Des/Assembly Top")
		(33 "B.Fab" user "Ref Des/Assembly Bottom")
	)
	(footprint ""
		(layer "B.Cu")
		(at 182.908448 -407.856182 90)
		(property "Reference" "R3909"
			(at 0 0 90)
			(layer "B.SilkS")
			(hide yes)
			(effects
				(font
					(size 1.27 1.27)
				)
				(justify mirror)
			)
		)
		(property "Value" ""
			(at 0 0 90)
			(layer "B.Fab")
			(effects
				(font
					(size 1.27 1.27)
				)
				(justify mirror)
			)
		)
		(duplicate_pad_numbers_are_jumpers no)
		(fp_line
			(start 0.7874 -0.4064)
			(end -0.7874 -0.4064)
			(stroke
				(width 0.1524)
				(type default)
			)
			(layer "B.SilkS")
		)
		(fp_line
			(start -0.7874 -0.4064)
			(end -0.7874 0.4064)
			(stroke
				(width 0.1524)
				(type default)
			)
			(layer "B.SilkS")
		)
		(fp_line
			(start 0.7874 0.4064)
			(end 0.7874 -0.4064)
			(stroke
				(width 0.1524)
				(type default)
			)
			(layer "B.SilkS")
		)
		(fp_line
			(start -0.7874 0.4064)
			(end 0.7874 0.4064)
			(stroke
				(width 0.1524)
				(type default)
			)
			(layer "B.SilkS")
		)
		(fp_line
			(start 0.67945 -0.305054)
			(end 0.12065 -0.305054)
			(stroke
				(width 0.1)
				(type default)
			)
			(layer "B.Fab")
		)
		(fp_line
			(start 0.12065 -0.305054)
			(end 0.12065 -0.2794)
			(stroke
				(width 0.1)
				(type default)
			)
			(layer "B.Fab")
		)
		(fp_line
			(start -0.12065 -0.3048)
			(end -0.67945 -0.3048)
			(stroke
				(width 0.1)
				(type default)
			)
			(layer "B.Fab")
		)
		(fp_line
			(start -0.67945 -0.3048)
			(end -0.67945 0.3048)
			(stroke
				(width 0.1)
				(type default)
			)
			(layer "B.Fab")
		)
		(fp_line
			(start 0.12065 -0.2794)
			(end -0.12065 -0.2794)
			(stroke
				(width 0.1)
				(type default)
			)
			(layer "B.Fab")
		)
		(fp_line
			(start -0.12065 -0.2794)
			(end -0.12065 -0.3048)
			(stroke
				(width 0.1)
				(type default)
			)
			(layer "B.Fab")
		)
		(fp_line
			(start 0.12065 0.2794)
			(end 0.12065 0.3048)
			(stroke
				(width 0.1)
				(type default)
			)
			(layer "B.Fab")
		)
		(fp_line
			(start -0.120396 0.2794)
			(end 0.12065 0.2794)
			(stroke
				(width 0.1)
				(type default)
			)
			(layer "B.Fab")
		)
		(fp_line
			(start 0.67945 0.3048)
			(end 0.67945 -0.305054)
			(stroke
				(width 0.1)
				(type default)
			)
			(layer "B.Fab")
		)
		(fp_line
			(start 0.12065 0.3048)
			(end 0.67945 0.3048)
			(stroke
				(width 0.1)
				(type default)
			)
			(layer "B.Fab")
		)
		(fp_line
			(start -0.120396 0.3048)
			(end -0.120396 0.2794)
			(stroke
				(width 0.1)
				(type default)
			)
			(layer "B.Fab")
		)
		(fp_line
			(start -0.67945 0.3048)
			(end -0.120396 0.3048)
			(stroke
				(width 0.1)
				(type default)
			)
			(layer "B.Fab")
		)
		(pad "1" smd circle
			(at 0.40005 0 270)
			(size 0 0)
			(layers "B.Cu" "B.Mask" "B.Paste")
			(net "SMB_SML1_PMBUS_HSC_SCL")
		)
		(pad "2" smd circle
			(at -0.40005 0 270)
			(size 0 0)
			(layers "B.Cu" "B.Mask" "B.Paste")
			(net "SMB_SML1_PMBUS_HSC_L_SCL")
		)
	)
	(footprint ""
		(layer "B.Cu")
		(at 418.373814 -321.549776 -90)
		(property "Reference" "C27"
			(at 0 0 90)
			(layer "B.SilkS")
			(hide yes)
			(effects
				(font
					(size 1.27 1.27)
				)
				(justify mirror)
			)
		)
		(property "Value" ""
			(at 0 0 90)
			(layer "B.Fab")
			(effects
				(font
					(size 1.27 1.27)
				)
				(justify mirror)
			)
		)
		(duplicate_pad_numbers_are_jumpers no)
		(fp_line
			(start -1.524 0.762)
			(end 1.524 0.762)
			(stroke
				(width 0.1524)
				(type default)
			)
			(layer "B.SilkS")
		)
		(fp_line
			(start 1.524 0.762)
			(end 1.524 -0.762)
			(stroke
				(width 0.1524)
				(type default)
			)
			(layer "B.SilkS")
		)
		(fp_line
			(start -1.524 -0.762)
			(end -1.524 0.762)
			(stroke
				(width 0.1524)
				(type default)
			)
			(layer "B.SilkS")
		)
		(fp_line
			(start 1.524 -0.762)
			(end -1.524 -0.762)
			(stroke
				(width 0.1524)
				(type default)
			)
			(layer "B.SilkS")
		)
		(fp_line
			(start -1.1049 0.724916)
			(end -1.1049 -0.724916)
			(stroke
				(width 0.1)
				(type default)
			)
			(layer "B.Fab")
		)
		(fp_line
			(start 1.1049 0.724916)
			(end -1.1049 0.724916)
			(stroke
				(width 0.1)
				(type default)
			)
			(layer "B.Fab")
		)
		(fp_line
			(start -1.1049 -0.724916)
			(end 1.1049 -0.724916)
			(stroke
				(width 0.1)
				(type default)
			)
			(layer "B.Fab")
		)
		(fp_line
			(start 1.1049 -0.724916)
			(end 1.1049 0.724916)
			(stroke
				(width 0.1)
				(type default)
			)
			(layer "B.Fab")
		)
		(pad "1" smd rect
			(at 0.889 0 270)
			(size 1.016 1.27)
			(layers "B.Cu" "B.Mask" "B.Paste")
			(net "P12V_S3_AUX_CPU0_NVDIMM")
		)
		(pad "2" smd rect
			(at -0.889 0 270)
			(size 1.016 1.27)
			(layers "B.Cu" "B.Mask" "B.Paste")
			(net "GND")
		)
	)
	(footprint ""
		(layer "B.Cu")
		(at 101.404928 -212.049868 180)
		(property "Reference" "C475"
			(at 0 0 0)
			(layer "B.SilkS")
			(hide yes)
			(effects
				(font
					(size 1.27 1.27)
				)
				(justify mirror)
			)
		)
		(property "Value" ""
			(at 0 0 0)
			(layer "B.Fab")
			(effects
				(font
					(size 1.27 1.27)
				)
				(justify mirror)
			)
		)
		(duplicate_pad_numbers_are_jumpers no)
		(fp_line
			(start 1.2954 0.5842)
			(end 1.2954 -0.5842)
			(stroke
				(width 0.1524)
				(type default)
			)
			(layer "B.SilkS")
		)
		(fp_line
			(start 1.2954 -0.5842)
			(end -1.2954 -0.5842)
			(stroke
				(width 0.1524)
				(type default)
			)
			(layer "B.SilkS")
		)
		(fp_line
			(start 0 -0.5842)
			(end 0 0.5842)
			(stroke
				(width 0.1524)
				(type default)
			)
			(layer "B.SilkS")
		)
		(fp_line
			(start -1.2954 0.5842)
			(end 1.2954 0.5842)
			(stroke
				(width 0.1524)
				(type default)
			)
			(layer "B.SilkS")
		)
		(fp_line
			(start -1.2954 -0.5842)
			(end -1.2954 0.5842)
			(stroke
				(width 0.1524)
				(type default)
			)
			(layer "B.SilkS")
		)
		(fp_line
			(start 1.1938 0.4064)
			(end 1.1938 -0.4064)
			(stroke
				(width 0.1)
				(type default)
			)
			(layer "B.Fab")
		)
		(fp_line
			(start 1.1938 -0.4064)
			(end 0.8636 -0.4064)
			(stroke
				(width 0.1)
				(type default)
			)
			(layer "B.Fab")
		)
		(fp_line
			(start 0.8636 0.4572)
			(end 0.8636 0.4064)
			(stroke
				(width 0.1)
				(type default)
			)
			(layer "B.Fab")
		)
		(fp_line
			(start 0.8636 0.4064)
			(end 1.1938 0.4064)
			(stroke
				(width 0.1)
				(type default)
			)
			(layer "B.Fab")
		)
		(fp_line
			(start 0.8636 -0.4064)
			(end 0.8636 -0.4572)
			(stroke
				(width 0.1)
				(type default)
			)
			(layer "B.Fab")
		)
		(fp_line
			(start 0.8636 -0.4572)
			(end -0.8636 -0.4572)
			(stroke
				(width 0.1)
				(type default)
			)
			(layer "B.Fab")
		)
		(fp_line
			(start -0.8636 0.4572)
			(end 0.8636 0.4572)
			(stroke
				(width 0.1)
				(type default)
			)
			(layer "B.Fab")
		)
		(fp_line
			(start -0.8636 0.4064)
			(end -0.8636 0.4572)
			(stroke
				(width 0.1)
				(type default)
			)
			(layer "B.Fab")
		)
		(fp_line
			(start -0.8636 -0.4064)
			(end -1.1938 -0.4064)
			(stroke
				(width 0.1)
				(type default)
			)
			(layer "B.Fab")
		)
		(fp_line
			(start -0.8636 -0.4572)
			(end -0.8636 -0.4064)
			(stroke
				(width 0.1)
				(type default)
			)
			(layer "B.Fab")
		)
		(fp_line
			(start -1.1938 0.4064)
			(end -0.8636 0.4064)
			(stroke
				(width 0.1)
				(type default)
			)
			(layer "B.Fab")
		)
		(fp_line
			(start -1.1938 -0.4064)
			(end -1.1938 0.4064)
			(stroke
				(width 0.1)
				(type default)
			)
			(layer "B.Fab")
		)
		(pad "1" smd rect
			(at 0.7366 0 90)
			(size 0.7112 0.8128)
			(layers "B.Cu" "B.Mask" "B.Paste")
			(net "PVCCFA_EHV_CPU1")
		)
		(pad "2" smd rect
			(at -0.7366 0 90)
			(size 0.7112 0.8128)
			(layers "B.Cu" "B.Mask" "B.Paste")
			(net "GND")
		)
	)
)
